(kicad_pcb
	(version 20260206)
	(generator "pcbnew")
	(generator_version "10.0")
	(general
		(thickness 1.6)
		(legacy_teardrops no)
	)
	(paper "A4")
	(title_block
		(title "01162023_DA0F0TEBIF0_F0T_Expander_BD_F_brd_V02_OCP.brd")
		(comment 1 "Grand Teton / footprints 7991-7998 of 9728")
	)
	(layers
		(0 "F.Cu" signal "TOP")
		(4 "In1.Cu" signal "GND")
		(6 "In2.Cu" signal "VCC")
		(8 "In3.Cu" signal "VCC1")
		(10 "In4.Cu" signal "GND1")
		(12 "In5.Cu" signal "IN1")
		(14 "In6.Cu" signal "GND2")
		(16 "In7.Cu" signal "IN2")
		(18 "In8.Cu" signal "GND3")
		(20 "In9.Cu" signal "IN3")
		(22 "In10.Cu" signal "GND4")
		(24 "In11.Cu" signal "IN4")
		(26 "In12.Cu" signal "GND5")
		(28 "In13.Cu" signal "IN5")
		(30 "In14.Cu" signal "GND6")
		(32 "In15.Cu" signal "IN6")
		(34 "In16.Cu" signal "GND7")
		(2 "B.Cu" signal "BOTTOM")
		(9 "F.Adhes" user "F.Adhesive")
		(11 "B.Adhes" user "B.Adhesive")
		(13 "F.Paste" user "Package Geometry/Pastemask Top")
		(15 "B.Paste" user "Package Geometry/Pastemask Bottom")
		(5 "F.SilkS" user "Ref Des/Silkscreen Top")
		(7 "B.SilkS" user "Ref Des/Silkscreen Bottom")
		(1 "F.Mask" user "Board Geometry/Soldermask Top")
		(3 "B.Mask" user "Board Geometry/Soldermask Bottom")
		(17 "Dwgs.User" user "User.Drawings")
		(19 "Cmts.User" user "User.Comments")
		(21 "Eco1.User" user "User.Eco1")
		(23 "Eco2.User" user "User.Eco2")
		(25 "Edge.Cuts" user "Board Geometry/Outline")
		(27 "Margin" user)
		(31 "F.CrtYd" user "Package Geometry/Place Bound Top")
		(29 "B.CrtYd" user "Package Geometry/Place Bound Bottom")
		(35 "F.Fab" user "Ref Des/Assembly Top")
		(33 "B.Fab" user "Ref Des/Assembly Bottom")
	)
	(footprint ""
		(layer "B.Cu")
		(at 173.375066 -286.399732 90)
		(property "Reference" "C3125"
			(at 0 0 90)
			(layer "B.SilkS")
			(hide yes)
			(effects
				(font
					(size 1.27 1.27)
				)
				(justify mirror)
			)
		)
		(property "Value" ""
			(at 0 0 90)
			(layer "B.Fab")
			(effects
				(font
					(size 1.27 1.27)
				)
				(justify mirror)
			)
		)
		(duplicate_pad_numbers_are_jumpers no)
		(fp_line
			(start 0.299974 -0.150114)
			(end -0.299974 -0.150114)
			(stroke
				(width 0.1)
				(type default)
			)
			(layer "B.Fab")
		)
		(fp_line
			(start -0.299974 -0.150114)
			(end -0.299974 0.150114)
			(stroke
				(width 0.1)
				(type default)
			)
			(layer "B.Fab")
		)
		(fp_line
			(start 0.299974 0.150114)
			(end 0.299974 -0.150114)
			(stroke
				(width 0.1)
				(type default)
			)
			(layer "B.Fab")
		)
		(fp_line
			(start -0.299974 0.150114)
			(end 0.299974 0.150114)
			(stroke
				(width 0.1)
				(type default)
			)
			(layer "B.Fab")
		)
		(pad "1" smd rect
			(at 0.2667 0 270)
			(size 0.3048 0.381)
			(layers "B.Cu" "B.Mask" "B.Paste")
			(net "P1V25_SERDES_VDDPLL_PEX1")
		)
		(pad "2" smd rect
			(at -0.2667 0 270)
			(size 0.3048 0.381)
			(layers "B.Cu" "B.Mask" "B.Paste")
			(net "GND")
		)
	)
	(footprint ""
		(layer "B.Cu")
		(at 398.925034 -293.99992 90)
		(property "Reference" "C1915"
			(at 0 0 90)
			(layer "B.SilkS")
			(hide yes)
			(effects
				(font
					(size 1.27 1.27)
				)
				(justify mirror)
			)
		)
		(property "Value" ""
			(at 0 0 90)
			(layer "B.Fab")
			(effects
				(font
					(size 1.27 1.27)
				)
				(justify mirror)
			)
		)
		(duplicate_pad_numbers_are_jumpers no)
		(fp_line
			(start 0.299974 -0.150114)
			(end -0.299974 -0.150114)
			(stroke
				(width 0.1)
				(type default)
			)
			(layer "B.Fab")
		)
		(fp_line
			(start -0.299974 -0.150114)
			(end -0.299974 0.150114)
			(stroke
				(width 0.1)
				(type default)
			)
			(layer "B.Fab")
		)
		(fp_line
			(start 0.299974 0.150114)
			(end 0.299974 -0.150114)
			(stroke
				(width 0.1)
				(type default)
			)
			(layer "B.Fab")
		)
		(fp_line
			(start -0.299974 0.150114)
			(end 0.299974 0.150114)
			(stroke
				(width 0.1)
				(type default)
			)
			(layer "B.Fab")
		)
		(pad "1" smd rect
			(at 0.2667 0 270)
			(size 0.3048 0.381)
			(layers "B.Cu" "B.Mask" "B.Paste")
			(net "P0V8_PEX3")
		)
		(pad "2" smd rect
			(at -0.2667 0 270)
			(size 0.3048 0.381)
			(layers "B.Cu" "B.Mask" "B.Paste")
			(net "GND")
		)
	)
	(footprint ""
		(layer "B.Cu")
		(at 255.63068 -88.634316)
		(property "Reference" "C2642"
			(at 0 0 0)
			(layer "B.SilkS")
			(hide yes)
			(effects
				(font
					(size 1.27 1.27)
				)
				(justify mirror)
			)
		)
		(property "Value" ""
			(at 0 0 0)
			(layer "B.Fab")
			(effects
				(font
					(size 1.27 1.27)
				)
				(justify mirror)
			)
		)
		(duplicate_pad_numbers_are_jumpers no)
		(fp_line
			(start -1.2954 -0.5842)
			(end -1.2954 0.5842)
			(stroke
				(width 0.1524)
				(type default)
			)
			(layer "B.SilkS")
		)
		(fp_line
			(start -1.2954 0.5842)
			(end 1.2954 0.5842)
			(stroke
				(width 0.1524)
				(type default)
			)
			(layer "B.SilkS")
		)
		(fp_line
			(start 1.2954 -0.5842)
			(end -1.2954 -0.5842)
			(stroke
				(width 0.1524)
				(type default)
			)
			(layer "B.SilkS")
		)
		(fp_line
			(start 1.2954 0.5842)
			(end 1.2954 -0.5842)
			(stroke
				(width 0.1524)
				(type default)
			)
			(layer "B.SilkS")
		)
		(fp_line
			(start -1.1938 -0.4064)
			(end -1.1938 0.4064)
			(stroke
				(width 0.1)
				(type default)
			)
			(layer "B.Fab")
		)
		(fp_line
			(start -1.1938 0.4064)
			(end -0.8636 0.4064)
			(stroke
				(width 0.1)
				(type default)
			)
			(layer "B.Fab")
		)
		(fp_line
			(start -0.8636 -0.4572)
			(end -0.8636 -0.4064)
			(stroke
				(width 0.1)
				(type default)
			)
			(layer "B.Fab")
		)
		(fp_line
			(start -0.8636 -0.4064)
			(end -1.1938 -0.4064)
			(stroke
				(width 0.1)
				(type default)
			)
			(layer "B.Fab")
		)
		(fp_line
			(start -0.8636 0.4064)
			(end -0.8636 0.4572)
			(stroke
				(width 0.1)
				(type default)
			)
			(layer "B.Fab")
		)
		(fp_line
			(start -0.8636 0.4572)
			(end 0.8636 0.4572)
			(stroke
				(width 0.1)
				(type default)
			)
			(layer "B.Fab")
		)
		(fp_line
			(start 0.8636 -0.4572)
			(end -0.8636 -0.4572)
			(stroke
				(width 0.1)
				(type default)
			)
			(layer "B.Fab")
		)
		(fp_line
			(start 0.8636 -0.4064)
			(end 0.8636 -0.4572)
			(stroke
				(width 0.1)
				(type default)
			)
			(layer "B.Fab")
		)
		(fp_line
			(start 0.8636 0.4064)
			(end 1.1938 0.4064)
			(stroke
				(width 0.1)
				(type default)
			)
			(layer "B.Fab")
		)
		(fp_line
			(start 0.8636 0.4572)
			(end 0.8636 0.4064)
			(stroke
				(width 0.1)
				(type default)
			)
			(layer "B.Fab")
		)
		(fp_line
			(start 1.1938 -0.4064)
			(end 0.8636 -0.4064)
			(stroke
				(width 0.1)
				(type default)
			)
			(layer "B.Fab")
		)
		(fp_line
			(start 1.1938 0.4064)
			(end 1.1938 -0.4064)
			(stroke
				(width 0.1)
				(type default)
			)
			(layer "B.Fab")
		)
		(pad "1" smd rect
			(at 0.7366 0 270)
			(size 0.7112 0.8128)
			(layers "B.Cu" "B.Mask" "B.Paste")
			(net "P3V3_CLK_GEN_VDDA25M_CK440")
		)
		(pad "2" smd rect
			(at -0.7366 0 270)
			(size 0.7112 0.8128)
			(layers "B.Cu" "B.Mask" "B.Paste")
			(net "GND")
		)
	)
	(footprint ""
		(layer "B.Cu")
		(at 256.87401 -223.315276 180)
		(property "Reference" "C2406"
			(at 0 0 0)
			(layer "B.SilkS")
			(hide yes)
			(effects
				(font
					(size 1.27 1.27)
				)
				(justify mirror)
			)
		)
		(property "Value" ""
			(at 0 0 0)
			(layer "B.Fab")
			(effects
				(font
					(size 1.27 1.27)
				)
				(justify mirror)
			)
		)
		(duplicate_pad_numbers_are_jumpers no)
		(fp_line
			(start 0.7874 0.4064)
			(end 0.7874 -0.4064)
			(stroke
				(width 0.1524)
				(type default)
			)
			(layer "B.SilkS")
		)
		(fp_line
			(start 0.7874 -0.4064)
			(end -0.7874 -0.4064)
			(stroke
				(width 0.1524)
				(type default)
			)
			(layer "B.SilkS")
		)
		(fp_line
			(start -0.7874 0.4064)
			(end 0.7874 0.4064)
			(stroke
				(width 0.1524)
				(type default)
			)
			(layer "B.SilkS")
		)
		(fp_line
			(start -0.7874 -0.4064)
			(end -0.7874 0.4064)
			(stroke
				(width 0.1524)
				(type default)
			)
			(layer "B.SilkS")
		)
		(fp_line
			(start 0.67945 0.3048)
			(end 0.67945 -0.305054)
			(stroke
				(width 0.1)
				(type default)
			)
			(layer "B.Fab")
		)
		(fp_line
			(start 0.67945 -0.305054)
			(end 0.12065 -0.305054)
			(stroke
				(width 0.1)
				(type default)
			)
			(layer "B.Fab")
		)
		(fp_line
			(start 0.12065 0.3048)
			(end 0.67945 0.3048)
			(stroke
				(width 0.1)
				(type default)
			)
			(layer "B.Fab")
		)
		(fp_line
			(start 0.12065 0.2794)
			(end 0.12065 0.3048)
			(stroke
				(width 0.1)
				(type default)
			)
			(layer "B.Fab")
		)
		(fp_line
			(start 0.12065 -0.2794)
			(end -0.12065 -0.2794)
			(stroke
				(width 0.1)
				(type default)
			)
			(layer "B.Fab")
		)
		(fp_line
			(start 0.12065 -0.305054)
			(end 0.12065 -0.2794)
			(stroke
				(width 0.1)
				(type default)
			)
			(layer "B.Fab")
		)
		(fp_line
			(start -0.120396 0.3048)
			(end -0.120396 0.2794)
			(stroke
				(width 0.1)
				(type default)
			)
			(layer "B.Fab")
		)
		(fp_line
			(start -0.120396 0.2794)
			(end 0.12065 0.2794)
			(stroke
				(width 0.1)
				(type default)
			)
			(layer "B.Fab")
		)
		(fp_line
			(start -0.12065 -0.2794)
			(end -0.12065 -0.3048)
			(stroke
				(width 0.1)
				(type default)
			)
			(layer "B.Fab")
		)
		(fp_line
			(start -0.12065 -0.3048)
			(end -0.67945 -0.3048)
			(stroke
				(width 0.1)
				(type default)
			)
			(layer "B.Fab")
		)
		(fp_line
			(start -0.67945 0.3048)
			(end -0.120396 0.3048)
			(stroke
				(width 0.1)
				(type default)
			)
			(layer "B.Fab")
		)
		(fp_line
			(start -0.67945 -0.3048)
			(end -0.67945 0.3048)
			(stroke
				(width 0.1)
				(type default)
			)
			(layer "B.Fab")
		)
		(pad "1" smd circle
			(at 0.40005 0)
			(size 0 0)
			(layers "B.Cu" "B.Mask" "B.Paste")
			(net "GND")
		)
		(pad "2" smd circle
			(at -0.40005 0)
			(size 0 0)
			(layers "B.Cu" "B.Mask" "B.Paste")
			(net "P1V8_PEX")
		)
	)
	(footprint ""
		(layer "B.Cu")
		(at 163.874958 -300.858174 -90)
		(property "Reference" "C3196"
			(at 0 0 90)
			(layer "B.SilkS")
			(hide yes)
			(effects
				(font
					(size 1.27 1.27)
				)
				(justify mirror)
			)
		)
		(property "Value" ""
			(at 0 0 90)
			(layer "B.Fab")
			(effects
				(font
					(size 1.27 1.27)
				)
				(justify mirror)
			)
		)
		(duplicate_pad_numbers_are_jumpers no)
		(fp_line
			(start -0.299974 0.150114)
			(end 0.299974 0.150114)
			(stroke
				(width 0.1)
				(type default)
			)
			(layer "B.Fab")
		)
		(fp_line
			(start 0.299974 0.150114)
			(end 0.299974 -0.150114)
			(stroke
				(width 0.1)
				(type default)
			)
			(layer "B.Fab")
		)
		(fp_line
			(start -0.299974 -0.150114)
			(end -0.299974 0.150114)
			(stroke
				(width 0.1)
				(type default)
			)
			(layer "B.Fab")
		)
		(fp_line
			(start 0.299974 -0.150114)
			(end -0.299974 -0.150114)
			(stroke
				(width 0.1)
				(type default)
			)
			(layer "B.Fab")
		)
		(pad "1" smd rect
			(at 0.2667 0 90)
			(size 0.3048 0.381)
			(layers "B.Cu" "B.Mask" "B.Paste")
			(net "PCEPLL0_VDDA18_PEX1")
		)
		(pad "2" smd rect
			(at -0.2667 0 90)
			(size 0.3048 0.381)
			(layers "B.Cu" "B.Mask" "B.Paste")
			(net "GND")
		)
	)
	(footprint ""
		(layer "B.Cu")
		(at 238.106712 -52.507642 90)
		(property "Reference" "C2893"
			(at 0 0 90)
			(layer "B.SilkS")
			(hide yes)
			(effects
				(font
					(size 1.27 1.27)
				)
				(justify mirror)
			)
		)
		(property "Value" ""
			(at 0 0 90)
			(layer "B.Fab")
			(effects
				(font
					(size 1.27 1.27)
				)
				(justify mirror)
			)
		)
		(duplicate_pad_numbers_are_jumpers no)
		(fp_line
			(start 0.7874 -0.4064)
			(end -0.7874 -0.4064)
			(stroke
				(width 0.1524)
				(type default)
			)
			(layer "B.SilkS")
		)
		(fp_line
			(start -0.7874 -0.4064)
			(end -0.7874 0.4064)
			(stroke
				(width 0.1524)
				(type default)
			)
			(layer "B.SilkS")
		)
		(fp_line
			(start 0.7874 0.4064)
			(end 0.7874 -0.4064)
			(stroke
				(width 0.1524)
				(type default)
			)
			(layer "B.SilkS")
		)
		(fp_line
			(start -0.7874 0.4064)
			(end 0.7874 0.4064)
			(stroke
				(width 0.1524)
				(type default)
			)
			(layer "B.SilkS")
		)
		(fp_line
			(start 0.67945 -0.305054)
			(end 0.12065 -0.305054)
			(stroke
				(width 0.1)
				(type default)
			)
			(layer "B.Fab")
		)
		(fp_line
			(start 0.12065 -0.305054)
			(end 0.12065 -0.2794)
			(stroke
				(width 0.1)
				(type default)
			)
			(layer "B.Fab")
		)
		(fp_line
			(start -0.12065 -0.3048)
			(end -0.67945 -0.3048)
			(stroke
				(width 0.1)
				(type default)
			)
			(layer "B.Fab")
		)
		(fp_line
			(start -0.67945 -0.3048)
			(end -0.67945 0.3048)
			(stroke
				(width 0.1)
				(type default)
			)
			(layer "B.Fab")
		)
		(fp_line
			(start 0.12065 -0.2794)
			(end -0.12065 -0.2794)
			(stroke
				(width 0.1)
				(type default)
			)
			(layer "B.Fab")
		)
		(fp_line
			(start -0.12065 -0.2794)
			(end -0.12065 -0.3048)
			(stroke
				(width 0.1)
				(type default)
			)
			(layer "B.Fab")
		)
		(fp_line
			(start 0.12065 0.2794)
			(end 0.12065 0.3048)
			(stroke
				(width 0.1)
				(type default)
			)
			(layer "B.Fab")
		)
		(fp_line
			(start -0.120396 0.2794)
			(end 0.12065 0.2794)
			(stroke
				(width 0.1)
				(type default)
			)
			(layer "B.Fab")
		)
		(fp_line
			(start 0.67945 0.3048)
			(end 0.67945 -0.305054)
			(stroke
				(width 0.1)
				(type default)
			)
			(layer "B.Fab")
		)
		(fp_line
			(start 0.12065 0.3048)
			(end 0.67945 0.3048)
			(stroke
				(width 0.1)
				(type default)
			)
			(layer "B.Fab")
		)
		(fp_line
			(start -0.120396 0.3048)
			(end -0.120396 0.2794)
			(stroke
				(width 0.1)
				(type default)
			)
			(layer "B.Fab")
		)
		(fp_line
			(start -0.67945 0.3048)
			(end -0.120396 0.3048)
			(stroke
				(width 0.1)
				(type default)
			)
			(layer "B.Fab")
		)
		(pad "1" smd circle
			(at 0.40005 0 270)
			(size 0 0)
			(layers "B.Cu" "B.Mask" "B.Paste")
			(net "SSD8_AUX_P3V3_EN_R")
		)
		(pad "2" smd circle
			(at -0.40005 0 270)
			(size 0 0)
			(layers "B.Cu" "B.Mask" "B.Paste")
			(net "GND")
		)
	)
	(footprint ""
		(layer "B.Cu")
		(at 334.49387 -224.786952)
		(property "Reference" "C2085"
			(at 0 0 0)
			(layer "B.SilkS")
			(hide yes)
			(effects
				(font
					(size 1.27 1.27)
				)
				(justify mirror)
			)
		)
		(property "Value" ""
			(at 0 0 0)
			(layer "B.Fab")
			(effects
				(font
					(size 1.27 1.27)
				)
				(justify mirror)
			)
		)
		(duplicate_pad_numbers_are_jumpers no)
		(fp_line
			(start -0.69215 -0.2921)
			(end -0.69215 0.2921)
			(stroke
				(width 0.1524)
				(type default)
			)
			(layer "B.SilkS")
		)
		(fp_line
			(start -0.69215 0.2921)
			(end 0.69215 0.2921)
			(stroke
				(width 0.1524)
				(type default)
			)
			(layer "B.SilkS")
		)
		(fp_line
			(start 0.69215 -0.2921)
			(end -0.69215 -0.2921)
			(stroke
				(width 0.1524)
				(type default)
			)
			(layer "B.SilkS")
		)
		(fp_line
			(start 0.69215 0.2921)
			(end 0.69215 -0.2921)
			(stroke
				(width 0.1524)
				(type default)
			)
			(layer "B.SilkS")
		)
		(fp_line
			(start -0.51435 -0.2794)
			(end -0.51435 0.2794)
			(stroke
				(width 0.1)
				(type default)
			)
			(layer "B.Fab")
		)
		(fp_line
			(start -0.51435 0.2794)
			(end 0.51435 0.2794)
			(stroke
				(width 0.1)
				(type default)
			)
			(layer "B.Fab")
		)
		(fp_line
			(start 0.51435 -0.2794)
			(end -0.51435 -0.2794)
			(stroke
				(width 0.1)
				(type default)
			)
			(layer "B.Fab")
		)
		(fp_line
			(start 0.51435 0.2794)
			(end 0.51435 -0.2794)
			(stroke
				(width 0.1)
				(type default)
			)
			(layer "B.Fab")
		)
		(pad "1" smd circle
			(at 0.40005 0 180)
			(size 0 0)
			(layers "B.Cu" "B.Mask" "B.Paste")
			(net "P3V3_FPGA_VCCIO5")
		)
		(pad "2" smd circle
			(at -0.40005 0 180)
			(size 0 0)
			(layers "B.Cu" "B.Mask" "B.Paste")
			(net "GND")
		)
		(zone
			(layer "B.Cu")
			(hatch none 0.5)
			(connect_pads
				(clearance 0)
			)
			(min_thickness 0.25)
			(keepout
				(tracks not_allowed)
				(vias allowed)
				(pads allowed)
				(copperpour not_allowed)
				(footprints allowed)
			)
			(placement
				(enabled no)
				(sheetname "")
			)
			(fill
				(thermal_gap 0.5)
				(thermal_bridge_width 0.5)
				(island_removal_mode 0)
			)
			(polygon
				(pts
					(xy 334.68437 -224.699322) (xy 334.59293 -224.641156) (xy 334.39354 -224.641156) (xy 334.30337 -224.699322)
					(xy 334.30337 -224.874582) (xy 334.39354 -224.933002) (xy 334.59293 -224.933002) (xy 334.68437 -224.874836)
				)
			)
		)
	)
	(footprint ""
		(layer "B.Cu")
		(at 232.651046 -144.618202 90)
		(property "Reference" "C2789"
			(at 0 0 90)
			(layer "B.SilkS")
			(hide yes)
			(effects
				(font
					(size 1.27 1.27)
				)
				(justify mirror)
			)
		)
		(property "Value" ""
			(at 0 0 90)
			(layer "B.Fab")
			(effects
				(font
					(size 1.27 1.27)
				)
				(justify mirror)
			)
		)
		(duplicate_pad_numbers_are_jumpers no)
		(fp_line
			(start 1.2954 -0.5842)
			(end -1.2954 -0.5842)
			(stroke
				(width 0.1524)
				(type default)
			)
			(layer "B.SilkS")
		)
		(fp_line
			(start -1.2954 -0.5842)
			(end -1.2954 0.5842)
			(stroke
				(width 0.1524)
				(type default)
			)
			(layer "B.SilkS")
		)
		(fp_line
			(start 1.2954 0.5842)
			(end 1.2954 -0.5842)
			(stroke
				(width 0.1524)
				(type default)
			)
			(layer "B.SilkS")
		)
		(fp_line
			(start -1.2954 0.5842)
			(end 1.2954 0.5842)
			(stroke
				(width 0.1524)
				(type default)
			)
			(layer "B.SilkS")
		)
		(fp_line
			(start 0.8636 -0.4572)
			(end -0.8636 -0.4572)
			(stroke
				(width 0.1)
				(type default)
			)
			(layer "B.Fab")
		)
		(fp_line
			(start -0.8636 -0.4572)
			(end -0.8636 -0.4064)
			(stroke
				(width 0.1)
				(type default)
			)
			(layer "B.Fab")
		)
		(fp_line
			(start 1.1938 -0.4064)
			(end 0.8636 -0.4064)
			(stroke
				(width 0.1)
				(type default)
			)
			(layer "B.Fab")
		)
		(fp_line
			(start 0.8636 -0.4064)
			(end 0.8636 -0.4572)
			(stroke
				(width 0.1)
				(type default)
			)
			(layer "B.Fab")
		)
		(fp_line
			(start -0.8636 -0.4064)
			(end -1.1938 -0.4064)
			(stroke
				(width 0.1)
				(type default)
			)
			(layer "B.Fab")
		)
		(fp_line
			(start -1.1938 -0.4064)
			(end -1.1938 0.4064)
			(stroke
				(width 0.1)
				(type default)
			)
			(layer "B.Fab")
		)
		(fp_line
			(start 1.1938 0.4064)
			(end 1.1938 -0.4064)
			(stroke
				(width 0.1)
				(type default)
			)
			(layer "B.Fab")
		)
		(fp_line
			(start 0.8636 0.4064)
			(end 1.1938 0.4064)
			(stroke
				(width 0.1)
				(type default)
			)
			(layer "B.Fab")
		)
		(fp_line
			(start -0.8636 0.4064)
			(end -0.8636 0.4572)
			(stroke
				(width 0.1)
				(type default)
			)
			(layer "B.Fab")
		)
		(fp_line
			(start -1.1938 0.4064)
			(end -0.8636 0.4064)
			(stroke
				(width 0.1)
				(type default)
			)
			(layer "B.Fab")
		)
		(fp_line
			(start 0.8636 0.4572)
			(end 0.8636 0.4064)
			(stroke
				(width 0.1)
				(type default)
			)
			(layer "B.Fab")
		)
		(fp_line
			(start -0.8636 0.4572)
			(end 0.8636 0.4572)
			(stroke
				(width 0.1)
				(type default)
			)
			(layer "B.Fab")
		)
		(pad "1" smd rect
			(at 0.7366 0)
			(size 0.7112 0.8128)
			(layers "B.Cu" "B.Mask" "B.Paste")
			(net "P3V3_CLK_GEN_VDDA100M_CK440_PEX")
		)
		(pad "2" smd rect
			(at -0.7366 0)
			(size 0.7112 0.8128)
			(layers "B.Cu" "B.Mask" "B.Paste")
			(net "GND")
		)
	)
)
